# S9S_MB_2U (Grand Teton) — schematic netlist excerpt (pin names and nets, part order shuffled) for the footprints in the layout excerpt that follows; sources: Cadence DE-HDL packaged netlist, KiCad conversion of 03242023_DA0F0TMBIJ0_F0T_Motherboard_J_brd_V01_OCP.brd

J41  SCONN168_ME1016810202011  IO  pkg CON_F168S2H7D_P0-6W2-95_LUH  page 240
  GND_A1  = SMB_OCP_SFF_3V3AUX_SCL_R0
  GND_A2  = SMB_OCP_SFF_3V3AUX_SDA_R0
  GND_A3  = SMB_HOST_3V3AUX_SCL_R0
  GND_A4  = SMB_HOST_3V3AUX_SDA_R0
  GND_A5  = SMB_VR_3V3AUX_SCL_R0
  GND_A6  = SMB_VR_3V3AUX_SDA_R0
  SMCLK  = SMB_SML1_PMBUS_3V3AUX_PCH_SCL_R
  SMDAT  = SMB_SML1_PMBUS_3V3AUX_PCH_SDA_R
  \smrst#\  = I3C_BMC_SWB_SCL
  \prsnta#\  = I3C_BMC_SWB_SDA
  \perst1#\  = SMB_OCP_V3_2_3V3AUX_SCL_R0
  \prsntb2#\  = SMB_OCP_V3_2_3V3AUX_SDA_R0
  GND_A13  = GND
  REFCLKN1  = CLK_100M_BMC_P3E_DP_R
  REFCLKP1  = CLK_100M_BMC_P3E_DN_R
  GND_A16  = GND
  PERN0  = P3E_PCH_BMC_TX_C_DP
  PERP0  = P3E_PCH_BMC_TX_C_DN
  GND_A19  = GND
  PERN1  = P3E_PCH_BMC_RX_DP
  PERP1  = P3E_PCH_BMC_RX_DN
  GND_A22  = GND
  PERN2  = SMB_PCIE0_3V3AUX_SCL
  PERP2  = SMB_PCIE0_3V3AUX_SDA
  GND_A25  = SMB_SML0_3V3AUX_SCL_R1
  PERN3  = SMB_SML0_3V3AUX_SDA_R1
  PERP3  = SMB_1_PLD_3V3AUX_SCL_R3
  GND_A28  = SMB_1_PLD_3V3AUX_SDA_R3
  GND_A29  = SMB_FAN_3V3AUX_SCL
  PERN4  = SMB_FAN_3V3AUX_SDA
  PERP4  = SMB_PCIE2_3V3AUX_SCL_R0
  GND_A32  = SMB_PCIE2_3V3AUX_SDA_R0
  PERN5  = GND
  PERP5  = JTAG_BMC_TCK
  GND_A35  = JTAG_BMC_TMS
  PERN6  = JTAG_BMC_TDI
  PERP6  = JTAG_BMC_TDO
  GND_A38  = SMB_PCIE3_3V3AUX_SCL_R
  PERN7  = SMB_PCIE3_3V3AUX_SDA_R
  PERP7  = SMB_S3M_CPU_3V3AUX_SCL_R0
  GND_A41  = SMB_S3M_CPU_3V3AUX_SDA_R0
  \prsntb1#\  = GND
  GND_A43  = FM_JTAG_BMC_MUX_SEL_FROM_BMC_R2
  PERN8  = PWRGD_PS_PWROK_R
  PERP8  = TP_HPM_STBY_EN
  GND_A46  = RST_MB_STBY_N
  PERN9  = FM_BMC_PWRBTN_OUT_R_N
  PERP9  = PWRGD_SYS_PWROK
  GND_A49  = JTAG_BMC_DBP_PREQ_N
  PERN10  = JTAG_DBP_BMC_PRDY_N
  PERP10  = RST_PLTRST_B_N
  GND_A52  = FM_UARTSW_MSB_R
  PERN11  = ROT_P1_RST_IND_N
  PERP11  = FM_BMC_INTRUDER_N
  GND_A55  = FM_UARTSW_LSB_R
  PERN12  = IRQ0_A57
  PERP12  = FM_SCM_PRSNT1_N
  GND_A58  = GND
  PERN13  = USB3_PCH_RX_DP<4>
  PERP13  = USB3_PCH_RX_DN<4>
  GND_A61  = GND
  PERN14  = TP_PCIE_HPM_RXP<1>
  PERP14  = TP_PCIE_HPM_RXN<1>
  GND_A64  = GND
  PERN15  = P2E_MB_BMC_RX_BUF_DP<0>
  PERP15  = P2E_MB_BMC_RX_BUF_DN<0>
  GND_A67  = GND
  USB_DATN  = CLK_100M_BMC_RC_DP
  USB_DATP  = CLK_100M_BMC_RC_DN
  \pwrbrk0#\  = GND
  \+12v_edge_b1\  = ESPI_HOST_LPC_BMC_CLK
  \+12v_edge_b2\  = ESPI_HOST_LPC_BMC_LFRAME_N
  \+12v_edge_b3\  = IRQ_ESPI_LPC_SERIRQ_ALERT_R_N
  \+12v_edge_b4\  = ESPI_BMC_LPC_RST_N
  \+12v_edge_b5\  = ESPI_LPC_LAD0_IO0
  \+12v_edge_b6\  = ESPI_LPC_LAD0_IO1
  \bif0#\  = ESPI_LPC_LAD0_IO2
  \bif1#\  = ESPI_LPC_LAD0_IO3
  \bif2#\  = FM_LPC_ESPI_SEL
  \perst0#\  = GND
  \+3.3v_edge\  = SPI_SYS_CLK
  AUX_PWR_EN  = SPI_SYS_CS0_N
  GND_B13  = SPI_SYS_MOSI
  REFCLKN0  = SPI_SYS_MISO
  REFCLKP0  = SPI_SYS_WP_IO2
  GND_B16  = SPI_SYS_HOLD_IO3
  PETN0  = GND
  PETP0  = CLK_50M_RMII_BMC_OCP
  GND_B19  = RMII_OCP_BMC_CRSDV
  PETN1  = RMII_BMC_OCP_TX_EN
  PETP1  = RMII_BMC_OCP_TXD_0
  GND_B22  = RMII_BMC_OCP_TXD_1
  PETN2  = RMII_BMC_OCP_RX_ER
  PETP2  = RMII_OCP_BMC_RXD_0
  GND_B25  = RMII_OCP_BMC_RXD_1
  PETN3  = GND
  PETP3  = PECI_BMC
  GND_B28  = PVCCIO_PECI_BMC
  GND_B29  = SGPIO_DO_0
  PETN4  = SGPIO_CLK_0
  PETP4  = SGPIO_DI_0
  GND_B32  = SGPIO_LD_0
  PETN5  = GND
  PETP5  = SGPIO_DO_1
  GND_B35  = SGPIO_CLK_1
  PETN6  = SGPIO_DI_1
  PETP6  = SGPIO_LD_1
  GND_B38  = GND
  PETN7  = RST_SGPIO_RESET_N
  PETP7  = IRQ_SGPIO_INTR_N
  GND_B41  = P3V_BAT_R1
  \prsntb0#\  = FM_AC_PWR_BTN_N
  GND_B43  = TP_SPI_2_PLD_CLK
  PETN8  = TP_SPI_2_PLD_CS_N
  PETP8  = TP_SPI_2_PLD_IO0
  GND_B46  = TP_SPI_2_PLD_IO1
  PETN9  = TP_SPI_2_PLD_IO2
  PETP9  = TP_SPI_2_PLD_IO3
  GND_B49  = GND
  PETN10  = USB2_HOST_BMC_B_DP
  PETP10  = USB2_HOST_BMC_B_DN
  GND_B52  = GND
  PETN11  = USB2_8_DP
  PETP11  = USB2_8_DN
  GND_B55  = GND
  PETN12  = USB2_HUB_2_BUF_EXT_DP
  PETP12  = USB2_HUB_2_BUF_EXT_DN
  GND_B58  = GND
  PETN13  = USB3_PCH_TX_BUF_C_DP<4>
  PETP13  = USB3_PCH_TX_BUF_C_DN<4>
  GND_B61  = GND
  PETN14  = TP_PCIE_HPM_TXP<1>
  PETP14  = TP_PCIE_HPM_TXN<1>
  GND_B64  = GND
  PETN15  = P2E_MB_BMC_TX_C_DP<0>
  PETP15  = P2E_MB_BMC_TX_C_DN<0>
  GND_B67  = GND
  RFU1_NC_B68  = TP_PCIE_HPM_TXP<3>
  RFU1_NC_B69  = TP_PCIE_HPM_TXN<3>
  \prsntb3#\  = GND
  G1  = GND
  G2  = GND
  G3  = GND
  G4  = GND
  G5  = GND
  \perst2#\  = P12V_SCM
  \perst3#\  = P12V_SCM
  \wake#\  = GND
  RBT_ARB_IN  = GND
  RBT_ARB_OUT  = I3C_SPD_DDRABCD_CPU0_BMC_R_SCL
  SLOT_ID1  = I3C_SPD_DDRABCD_CPU0_BMC_R_SDA
  RBT_TX_EN  = I3C_SPD_DDREFGH_CPU0_BMC_R_SCL
  RBT_TXD1  = I3C_SPD_DDREFGH_CPU0_BMC_R_SDA
  RBT_TXD0  = I3C_SPD_DDRABCD_CPU1_BMC_R_SCL
  GND_OA10  = I3C_SPD_DDRABCD_CPU1_BMC_R_SDA
  REFCLKN3  = I3C_SPD_DDREFGH_CPU1_BMC_R_SCL
  REFCLKP3  = I3C_SPD_DDREFGH_CPU1_BMC_R_SDA
  GND_OA13  = GND
  RBT_CLK_IN  = VIRTUAL_RESEAT
  NIC_PWR_GOOD  = P12V_SCM
  MAIN_PWR_EN  = P12V_SCM
  \ld#\  = PRSNT0_N
  DATA_IN  = GND
  DATA_OUT  = UART_BMC_BIC_TX
  CLK  = UART_BMC_BIC_BUF_RX
  SLOT_ID0  = GND
  RBT_RXD1  = USB2_7_R_DP
  RBT_RXD0  = USB2_7_R_DN
  GND_OB10  = GND
  REFCLKN2  = RST_SRST_PLD_BMC_N
  REFCLKP2  = SPI_TPM_CS_N
  GND_OB13  = H_CPU_CATERR_LVC2_BMC_N
  RBT_CRS_DV  = FM_SOL_UART_CH_SEL_R

(kicad_pcb
	(version 20260206)
	(generator "pcbnew")
	(generator_version "10.0")
	(general
		(thickness 1.6)
		(legacy_teardrops no)
	)
	(paper "A4")
	(title_block
		(title "03242023_DA0F0TMBIJ0_F0T_Motherboard_J_brd_V01_OCP.brd")
		(comment 1 "Grand Teton / footprint 3077 of 6105 (J41), pads 43-86 of 175")
	)
	(layers
		(0 "F.Cu" signal "TOP")
		(4 "In1.Cu" signal "GND")
		(6 "In2.Cu" signal "IN1")
		(8 "In3.Cu" signal "GND1")
		(10 "In4.Cu" signal "IN2")
		(12 "In5.Cu" signal "GND2")
		(14 "In6.Cu" signal "IN3")
		(16 "In7.Cu" signal "GND3")
		(18 "In8.Cu" signal "VCC")
		(20 "In9.Cu" signal "VCC1")
		(22 "In10.Cu" signal "GND4")
		(24 "In11.Cu" signal "IN4")
		(26 "In12.Cu" signal "GND5")
		(28 "In13.Cu" signal "IN5")
		(30 "In14.Cu" signal "GND6")
		(32 "In15.Cu" signal "IN6")
		(34 "In16.Cu" signal "GND7")
		(2 "B.Cu" signal "BOTTOM")
		(9 "F.Adhes" user "F.Adhesive")
		(11 "B.Adhes" user "B.Adhesive")
		(13 "F.Paste" user "Package Geometry/Pastemask Top")
		(15 "B.Paste" user "Package Geometry/Pastemask Bottom")
		(5 "F.SilkS" user "Ref Des/Silkscreen Top")
		(7 "B.SilkS" user "Ref Des/Silkscreen Bottom")
		(1 "F.Mask" user "Board Geometry/Soldermask Top")
		(3 "B.Mask" user "Board Geometry/Soldermask Bottom")
		(17 "Dwgs.User" user "User.Drawings")
		(19 "Cmts.User" user "User.Comments")
		(21 "Eco1.User" user "User.Eco1")
		(23 "Eco2.User" user "User.Eco2")
		(25 "Edge.Cuts" user "Board Geometry/Outline")
		(27 "Margin" user)
		(31 "F.CrtYd" user "Package Geometry/Place Bound Top")
		(29 "B.CrtYd" user "Package Geometry/Place Bound Bottom")
		(35 "F.Fab" user "Ref Des/Assembly Top")
		(33 "B.Fab" user "Ref Des/Assembly Bottom")
	)
	(footprint ""
		(layer "F.Cu")
		(at 160.402016 -10.850118 -90)
		(property "Reference" "J41"
			(at -12.075414 24.511762 0)
			(unlocked yes)
			(layer "F.SilkS")
			(effects
				(font
					(size 0.7874 0.5842)
					(thickness 0.1524)
				)
				(justify left)
			)
		)
		(property "Value" ""
			(at 0 0 270)
			(layer "F.Fab")
			(effects
				(font
					(size 1.27 1.27)
				)
			)
		)
		(duplicate_pad_numbers_are_jumpers no)
		(pad "A41" smd rect
			(at -2.750058 8.945118 180)
			(size 0.381 1.4478)
			(layers "F.Cu" "F.Mask" "F.Paste")
			(net "SMB_S3M_CPU_3V3AUX_SDA_R0")
		)
		(pad "A42" smd rect
			(at -2.750058 9.545066 180)
			(size 0.381 1.4478)
			(layers "F.Cu" "F.Mask" "F.Paste")
			(net "GND")
		)
		(pad "A43" smd rect
			(at -2.750058 14.454886 180)
			(size 0.381 1.4478)
			(layers "F.Cu" "F.Mask" "F.Paste")
			(net "FM_JTAG_BMC_MUX_SEL_FROM_BMC_R2")
		)
		(pad "A44" smd rect
			(at -2.750058 15.055088 180)
			(size 0.381 1.4478)
			(layers "F.Cu" "F.Mask" "F.Paste")
			(net "PWRGD_PS_PWROK_R")
		)
		(pad "A45" smd rect
			(at -2.750058 15.655036 180)
			(size 0.381 1.4478)
			(layers "F.Cu" "F.Mask" "F.Paste")
			(net "TP_HPM_STBY_EN")
		)
		(pad "A46" smd rect
			(at -2.750058 16.254984 180)
			(size 0.381 1.4478)
			(layers "F.Cu" "F.Mask" "F.Paste")
			(net "RST_MB_STBY_N")
		)
		(pad "A47" smd rect
			(at -2.750058 16.854932 180)
			(size 0.381 1.4478)
			(layers "F.Cu" "F.Mask" "F.Paste")
			(net "FM_BMC_PWRBTN_OUT_R_N")
		)
		(pad "A48" smd rect
			(at -2.750058 17.45488 180)
			(size 0.381 1.4478)
			(layers "F.Cu" "F.Mask" "F.Paste")
			(net "PWRGD_SYS_PWROK")
		)
		(pad "A49" smd rect
			(at -2.750058 18.055082 180)
			(size 0.381 1.4478)
			(layers "F.Cu" "F.Mask" "F.Paste")
			(net "JTAG_BMC_DBP_PREQ_N")
		)
		(pad "A50" smd rect
			(at -2.750058 18.65503 180)
			(size 0.381 1.4478)
			(layers "F.Cu" "F.Mask" "F.Paste")
			(net "JTAG_DBP_BMC_PRDY_N")
		)
		(pad "A51" smd rect
			(at -2.750058 19.254978 180)
			(size 0.381 1.4478)
			(layers "F.Cu" "F.Mask" "F.Paste")
			(net "RST_PLTRST_B_N")
		)
		(pad "A52" smd rect
			(at -2.750058 19.854926 180)
			(size 0.381 1.4478)
			(layers "F.Cu" "F.Mask" "F.Paste")
			(net "FM_UARTSW_MSB_R")
		)
		(pad "A53" smd rect
			(at -2.750058 20.455128 180)
			(size 0.381 1.4478)
			(layers "F.Cu" "F.Mask" "F.Paste")
			(net "ROT_P1_RST_IND_N")
		)
		(pad "A54" smd rect
			(at -2.750058 21.055076 180)
			(size 0.381 1.4478)
			(layers "F.Cu" "F.Mask" "F.Paste")
			(net "FM_BMC_INTRUDER_N")
		)
		(pad "A55" smd rect
			(at -2.750058 21.655024 180)
			(size 0.381 1.4478)
			(layers "F.Cu" "F.Mask" "F.Paste")
			(net "FM_UARTSW_LSB_R")
		)
		(pad "A56" smd rect
			(at -2.750058 22.254972 180)
			(size 0.381 1.4478)
			(layers "F.Cu" "F.Mask" "F.Paste")
			(net "IRQ0_A57")
		)
		(pad "A57" smd rect
			(at -2.750058 22.85492 180)
			(size 0.381 1.4478)
			(layers "F.Cu" "F.Mask" "F.Paste")
			(net "FM_SCM_PRSNT1_N")
		)
		(pad "A58" smd rect
			(at -2.750058 23.455122 180)
			(size 0.381 1.4478)
			(layers "F.Cu" "F.Mask" "F.Paste")
			(net "GND")
		)
		(pad "A59" smd rect
			(at -2.750058 24.05507 180)
			(size 0.381 1.4478)
			(layers "F.Cu" "F.Mask" "F.Paste")
			(net "USB3_PCH_RX_DP<4>")
		)
		(pad "A60" smd rect
			(at -2.750058 24.655018 180)
			(size 0.381 1.4478)
			(layers "F.Cu" "F.Mask" "F.Paste")
			(net "USB3_PCH_RX_DN<4>")
		)
		(pad "A61" smd rect
			(at -2.750058 25.254966 180)
			(size 0.381 1.4478)
			(layers "F.Cu" "F.Mask" "F.Paste")
			(net "GND")
		)
		(pad "A62" smd rect
			(at -2.750058 25.854914 180)
			(size 0.381 1.4478)
			(layers "F.Cu" "F.Mask" "F.Paste")
			(net "TP_PCIE_HPM_RXP<1>")
		)
		(pad "A63" smd rect
			(at -2.750058 26.455116 180)
			(size 0.381 1.4478)
			(layers "F.Cu" "F.Mask" "F.Paste")
			(net "TP_PCIE_HPM_RXN<1>")
		)
		(pad "A64" smd rect
			(at -2.750058 27.055064 180)
			(size 0.381 1.4478)
			(layers "F.Cu" "F.Mask" "F.Paste")
			(net "GND")
		)
		(pad "A65" smd rect
			(at -2.750058 27.655012 180)
			(size 0.381 1.4478)
			(layers "F.Cu" "F.Mask" "F.Paste")
			(net "P2E_MB_BMC_RX_BUF_DP<0>")
		)
		(pad "A66" smd rect
			(at -2.750058 28.25496 180)
			(size 0.381 1.4478)
			(layers "F.Cu" "F.Mask" "F.Paste")
			(net "P2E_MB_BMC_RX_BUF_DN<0>")
		)
		(pad "A67" smd rect
			(at -2.750058 28.854908 180)
			(size 0.381 1.4478)
			(layers "F.Cu" "F.Mask" "F.Paste")
			(net "GND")
		)
		(pad "A68" smd rect
			(at -2.750058 29.45511 180)
			(size 0.381 1.4478)
			(layers "F.Cu" "F.Mask" "F.Paste")
			(net "CLK_100M_BMC_RC_DP")
		)
		(pad "A69" smd rect
			(at -2.750058 30.055058 180)
			(size 0.381 1.4478)
			(layers "F.Cu" "F.Mask" "F.Paste")
			(net "CLK_100M_BMC_RC_DN")
		)
		(pad "A70" smd rect
			(at -2.750058 30.655006 180)
			(size 0.381 1.4478)
			(layers "F.Cu" "F.Mask" "F.Paste")
			(net "GND")
		)
		(pad "B1" smd rect
			(at -5.700014 -18.465038 180)
			(size 0.381 1.4478)
			(layers "F.Cu" "F.Mask" "F.Paste")
			(net "ESPI_HOST_LPC_BMC_CLK")
		)
		(pad "B2" smd rect
			(at -5.700014 -17.86509 180)
			(size 0.381 1.4478)
			(layers "F.Cu" "F.Mask" "F.Paste")
			(net "ESPI_HOST_LPC_BMC_LFRAME_N")
		)
		(pad "B3" smd rect
			(at -5.700014 -17.264888 180)
			(size 0.381 1.4478)
			(layers "F.Cu" "F.Mask" "F.Paste")
			(net "IRQ_ESPI_LPC_SERIRQ_ALERT_R_N")
		)
		(pad "B4" smd rect
			(at -5.700014 -16.66494 180)
			(size 0.381 1.4478)
			(layers "F.Cu" "F.Mask" "F.Paste")
			(net "ESPI_BMC_LPC_RST_N")
		)
		(pad "B5" smd rect
			(at -5.700014 -16.064992 180)
			(size 0.381 1.4478)
			(layers "F.Cu" "F.Mask" "F.Paste")
			(net "ESPI_LPC_LAD0_IO0")
		)
		(pad "B6" smd rect
			(at -5.700014 -15.465044 180)
			(size 0.381 1.4478)
			(layers "F.Cu" "F.Mask" "F.Paste")
			(net "ESPI_LPC_LAD0_IO1")
		)
		(pad "B7" smd rect
			(at -5.700014 -14.865096 180)
			(size 0.381 1.4478)
			(layers "F.Cu" "F.Mask" "F.Paste")
			(net "ESPI_LPC_LAD0_IO2")
		)
		(pad "B8" smd rect
			(at -5.700014 -14.264894 180)
			(size 0.381 1.4478)
			(layers "F.Cu" "F.Mask" "F.Paste")
			(net "ESPI_LPC_LAD0_IO3")
		)
		(pad "B9" smd rect
			(at -5.700014 -13.664946 180)
			(size 0.381 1.4478)
			(layers "F.Cu" "F.Mask" "F.Paste")
			(net "FM_LPC_ESPI_SEL")
		)
		(pad "B10" smd rect
			(at -5.700014 -13.064998 180)
			(size 0.381 1.4478)
			(layers "F.Cu" "F.Mask" "F.Paste")
			(net "GND")
		)
		(pad "B11" smd rect
			(at -5.700014 -12.46505 180)
			(size 0.381 1.4478)
			(layers "F.Cu" "F.Mask" "F.Paste")
			(net "SPI_SYS_CLK")
		)
		(pad "B12" smd rect
			(at -5.700014 -11.865102 180)
			(size 0.381 1.4478)
			(layers "F.Cu" "F.Mask" "F.Paste")
			(net "SPI_SYS_CS0_N")
		)
		(pad "B13" smd rect
			(at -5.700014 -11.2649 180)
			(size 0.381 1.4478)
			(layers "F.Cu" "F.Mask" "F.Paste")
			(net "SPI_SYS_MOSI")
		)
		(pad "B14" smd rect
			(at -5.700014 -10.664952 180)
			(size 0.381 1.4478)
			(layers "F.Cu" "F.Mask" "F.Paste")
			(net "SPI_SYS_MISO")
		)
	)
)
